# T6G (Grand Teton) — schematic netlist excerpt (pin names and nets, part order shuffled) for the footprints in the layout excerpt that follows; sources: Cadence DE-HDL packaged netlist, KiCad conversion of 04192023_DAF0TMB3IC0_F0TG_MB_C_brd_V02_OCP.brd

C252  Q_CAP  22UF 4V 20% X6S  pkg C0402  page 69 : A = PVDDCR_CPU0_P0 ; B = GND
PC105  Q_CAPP  220UF 4V 20% SPCAP  pkg SMLF  page 211 : A = PVDDCR_CPU0_P1 ; B = GND

(kicad_pcb
	(version 20260206)
	(generator "pcbnew")
	(generator_version "10.0")
	(general
		(thickness 1.6)
		(legacy_teardrops no)
	)
	(paper "A4")
	(title_block
		(title "04192023_DAF0TMB3IC0_F0TG_MB_C_brd_V02_OCP.brd")
		(comment 1 "Grand Teton / footprints 7475-7476 of 8354")
	)
	(layers
		(0 "F.Cu" signal "TOP")
		(4 "In1.Cu" signal "GND")
		(6 "In2.Cu" signal "IN1")
		(8 "In3.Cu" signal "GND1")
		(10 "In4.Cu" signal "IN2")
		(12 "In5.Cu" signal "GND2")
		(14 "In6.Cu" signal "IN3")
		(16 "In7.Cu" signal "GND3")
		(18 "In8.Cu" signal "VCC")
		(20 "In9.Cu" signal "VCC1")
		(22 "In10.Cu" signal "GND4")
		(24 "In11.Cu" signal "IN4")
		(26 "In12.Cu" signal "GND5")
		(28 "In13.Cu" signal "IN5")
		(30 "In14.Cu" signal "GND6")
		(32 "In15.Cu" signal "IN6")
		(34 "In16.Cu" signal "GND7")
		(2 "B.Cu" signal "BOTTOM")
		(9 "F.Adhes" user "F.Adhesive")
		(11 "B.Adhes" user "B.Adhesive")
		(13 "F.Paste" user "Package Geometry/Pastemask Top")
		(15 "B.Paste" user "Package Geometry/Pastemask Bottom")
		(5 "F.SilkS" user "Ref Des/Silkscreen Top")
		(7 "B.SilkS" user "Ref Des/Silkscreen Bottom")
		(1 "F.Mask" user "Board Geometry/Soldermask Top")
		(3 "B.Mask" user "Board Geometry/Soldermask Bottom")
		(17 "Dwgs.User" user "User.Drawings")
		(19 "Cmts.User" user "User.Comments")
		(21 "Eco1.User" user "User.Eco1")
		(23 "Eco2.User" user "User.Eco2")
		(25 "Edge.Cuts" user "Board Geometry/Outline")
		(27 "Margin" user)
		(31 "F.CrtYd" user "Package Geometry/Place Bound Top")
		(29 "B.CrtYd" user "Package Geometry/Place Bound Bottom")
		(35 "F.Fab" user "Ref Des/Assembly Top")
		(33 "B.Fab" user "Ref Des/Assembly Bottom")
	)
	(footprint ""
		(layer "B.Cu")
		(at 107.429554 -184.906412 90)
		(property "Reference" "PC105"
			(at 5.990336 1.013714 270)
			(unlocked yes)
			(layer "B.SilkS")
			(effects
				(font
					(size 0.7874 0.5842)
					(thickness 0.1524)
				)
				(justify left mirror)
			)
		)
		(property "Value" ""
			(at 0 0 90)
			(layer "B.Fab")
			(effects
				(font
					(size 1.27 1.27)
				)
				(justify mirror)
			)
		)
		(duplicate_pad_numbers_are_jumpers no)
		(fp_line
			(start 4.533392 -2.249932)
			(end -4.533392 -2.249932)
			(stroke
				(width 0.1524)
				(type default)
			)
			(layer "B.SilkS")
		)
		(fp_line
			(start -4.533392 -2.249932)
			(end -4.533392 2.249932)
			(stroke
				(width 0.1524)
				(type default)
			)
			(layer "B.SilkS")
		)
		(fp_line
			(start 4.533392 2.249932)
			(end 4.533392 -2.249932)
			(stroke
				(width 0.1524)
				(type default)
			)
			(layer "B.SilkS")
		)
		(fp_line
			(start -4.533392 2.249932)
			(end 4.533392 2.249932)
			(stroke
				(width 0.1524)
				(type default)
			)
			(layer "B.SilkS")
		)
		(fp_rect
			(start 4.533392 -2.326132)
			(end 5.39242 2.326132)
			(stroke
				(width 0)
				(type default)
			)
			(fill yes)
			(layer "B.SilkS")
		)
		(fp_line
			(start 3.750056 -2.249932)
			(end -3.750056 -2.249932)
			(stroke
				(width 0.1)
				(type default)
			)
			(layer "B.Fab")
		)
		(fp_line
			(start -3.750056 -2.249932)
			(end -3.750056 2.249932)
			(stroke
				(width 0.1)
				(type default)
			)
			(layer "B.Fab")
		)
		(fp_line
			(start 3.750056 2.249932)
			(end 3.750056 -2.249932)
			(stroke
				(width 0.1)
				(type default)
			)
			(layer "B.Fab")
		)
		(fp_line
			(start -3.750056 2.249932)
			(end 3.750056 2.249932)
			(stroke
				(width 0.1)
				(type default)
			)
			(layer "B.Fab")
		)
		(fp_text user "-"
			(at -4.8514 -0.14605 90)
			(unlocked yes)
			(layer "B.SilkS")
			(effects
				(font
					(size 1.905 1.4224)
					(thickness 0.1524)
				)
				(justify left mirror)
			)
		)
		(fp_text user "+"
			(at 6.322314 0.786384 0)
			(unlocked yes)
			(layer "B.SilkS")
			(effects
				(font
					(size 1.905 1.4224)
					(thickness 0.1524)
				)
				(justify left mirror)
			)
		)
		(fp_text user "-"
			(at -4.8514 -0.14605 90)
			(unlocked yes)
			(layer "B.Fab")
			(effects
				(font
					(size 1.905 1.4224)
					(thickness 0.1524)
				)
				(justify left mirror)
			)
		)
		(fp_text user "+"
			(at 6.322314 0.786384 0)
			(unlocked yes)
			(layer "B.Fab")
			(effects
				(font
					(size 1.905 1.4224)
					(thickness 0.1524)
				)
				(justify left mirror)
			)
		)
		(pad "1" smd rect
			(at 3.199892 0 270)
			(size 2.413 2.8194)
			(layers "B.Cu" "B.Mask" "B.Paste")
			(net "PVDDCR_CPU0_P1")
		)
		(pad "2" smd rect
			(at -3.199892 0 270)
			(size 2.413 2.8194)
			(layers "B.Cu" "B.Mask" "B.Paste")
			(net "GND")
		)
	)
	(footprint ""
		(layer "B.Cu")
		(at 355.009958 -245.487952 180)
		(property "Reference" "C252"
			(at 0 0 0)
			(layer "B.SilkS")
			(hide yes)
			(effects
				(font
					(size 1.27 1.27)
				)
				(justify mirror)
			)
		)
		(property "Value" ""
			(at 0 0 0)
			(layer "B.Fab")
			(effects
				(font
					(size 1.27 1.27)
				)
				(justify mirror)
			)
		)
		(duplicate_pad_numbers_are_jumpers no)
		(fp_line
			(start 0.7874 0.4064)
			(end 0.7874 -0.4064)
			(stroke
				(width 0.1524)
				(type default)
			)
			(layer "B.SilkS")
		)
		(fp_line
			(start 0.7874 -0.4064)
			(end -0.7874 -0.4064)
			(stroke
				(width 0.1524)
				(type default)
			)
			(layer "B.SilkS")
		)
		(fp_line
			(start -0.7874 0.4064)
			(end 0.7874 0.4064)
			(stroke
				(width 0.1524)
				(type default)
			)
			(layer "B.SilkS")
		)
		(fp_line
			(start -0.7874 -0.4064)
			(end -0.7874 0.4064)
			(stroke
				(width 0.1524)
				(type default)
			)
			(layer "B.SilkS")
		)
		(fp_line
			(start 0.67945 0.3048)
			(end 0.67945 -0.305054)
			(stroke
				(width 0.1)
				(type default)
			)
			(layer "B.Fab")
		)
		(fp_line
			(start 0.67945 -0.305054)
			(end 0.12065 -0.305054)
			(stroke
				(width 0.1)
				(type default)
			)
			(layer "B.Fab")
		)
		(fp_line
			(start 0.12065 0.3048)
			(end 0.67945 0.3048)
			(stroke
				(width 0.1)
				(type default)
			)
			(layer "B.Fab")
		)
		(fp_line
			(start 0.12065 0.2794)
			(end 0.12065 0.3048)
			(stroke
				(width 0.1)
				(type default)
			)
			(layer "B.Fab")
		)
		(fp_line
			(start 0.12065 -0.2794)
			(end -0.12065 -0.2794)
			(stroke
				(width 0.1)
				(type default)
			)
			(layer "B.Fab")
		)
		(fp_line
			(start 0.12065 -0.305054)
			(end 0.12065 -0.2794)
			(stroke
				(width 0.1)
				(type default)
			)
			(layer "B.Fab")
		)
		(fp_line
			(start -0.120396 0.3048)
			(end -0.120396 0.2794)
			(stroke
				(width 0.1)
				(type default)
			)
			(layer "B.Fab")
		)
		(fp_line
			(start -0.120396 0.2794)
			(end 0.12065 0.2794)
			(stroke
				(width 0.1)
				(type default)
			)
			(layer "B.Fab")
		)
		(fp_line
			(start -0.12065 -0.2794)
			(end -0.12065 -0.3048)
			(stroke
				(width 0.1)
				(type default)
			)
			(layer "B.Fab")
		)
		(fp_line
			(start -0.12065 -0.3048)
			(end -0.67945 -0.3048)
			(stroke
				(width 0.1)
				(type default)
			)
			(layer "B.Fab")
		)
		(fp_line
			(start -0.67945 0.3048)
			(end -0.120396 0.3048)
			(stroke
				(width 0.1)
				(type default)
			)
			(layer "B.Fab")
		)
		(fp_line
			(start -0.67945 -0.3048)
			(end -0.67945 0.3048)
			(stroke
				(width 0.1)
				(type default)
			)
			(layer "B.Fab")
		)
		(pad "1" smd circle
			(at 0.40005 0)
			(size 0 0)
			(layers "B.Cu" "B.Mask" "B.Paste")
			(net "PVDDCR_CPU0_P0")
		)
		(pad "2" smd circle
			(at -0.40005 0)
			(size 0 0)
			(layers "B.Cu" "B.Mask" "B.Paste")
			(net "GND")
		)
	)
)
